# T6G (Grand Teton) — schematic netlist excerpt (pin names and nets, part order shuffled) for the footprints in the layout excerpt that follows; sources: Cadence DE-HDL packaged netlist, KiCad conversion of 04192023_DAF0TMB3IC0_F0TG_MB_C_brd_V02_OCP.brd

J30  SCONN288_DDR506112002KQ  IO  pkg DDR288S_1-1VXC  page 101
  VIN_BULK0  = P12V_MEM_CPU1
  RFU0  = NC
  VIN_MGMT  = P3V3_AUX
  HSCL  = I3C_SPD_DDRD_CPU1_SCL
  HSDA  = I3C_SPD_DDRD_CPU1_SDA
  VSS0  = GND
  DQ0_A  = M_D_CPU1_SA_DQ<0>
  VSS1  = GND
  DQ1_A  = M_D_CPU1_SA_DQ<1>
  VSS2  = GND
  DQS0_A_T  = M_D_CPU1_SA_DQS_DP<0>
  DQS0_A_C  = M_D_CPU1_SA_DQS_DN<0>
  VSS3  = GND
  DQ4_A  = M_D_CPU1_SA_DQ<4>
  VSS4  = GND
  DQ5_A  = M_D_CPU1_SA_DQ<5>
  VSS5  = GND
  DQ8_A  = M_D_CPU1_SA_DQ<8>
  VSS6  = GND
  DQ9_A  = M_D_CPU1_SA_DQ<9>
  VSS7  = GND
  DQS1_A_T  = M_D_CPU1_SA_DQS_DP<1>
  DQS1_A_C  = M_D_CPU1_SA_DQS_DN<1>
  VSS8  = GND
  DQ12_A  = M_D_CPU1_SA_DQ<12>
  VSS9  = GND
  DQ13_A  = M_D_CPU1_SA_DQ<13>
  VSS10  = GND
  DQ16_A  = M_D_CPU1_SA_DQ<16>
  VSS11  = GND
  DQ17_A  = M_D_CPU1_SA_DQ<17>
  VSS12  = GND
  DQS2_A_T  = M_D_CPU1_SA_DQS_DP<2>
  DQS2_A_C  = M_D_CPU1_SA_DQS_DN<2>
  VSS13  = GND
  DQ20_A  = M_D_CPU1_SA_DQ<20>
  VSS14  = GND
  DQ21_A  = M_D_CPU1_SA_DQ<21>
  VSS15  = GND
  DQ24_A  = M_D_CPU1_SA_DQ<24>
  VSS16  = GND
  DQ25_A  = M_D_CPU1_SA_DQ<25>
  VSS17  = GND
  DQS3_A_T  = M_D_CPU1_SA_DQS_DP<3>
  DQS3_A_C  = M_D_CPU1_SA_DQS_DN<3>
  VSS18  = GND
  DQ28_A  = M_D_CPU1_SA_DQ<28>
  VSS19  = GND
  DQ29_A  = M_D_CPU1_SA_DQ<29>
  VSS20  = GND
  CB0_A  = M_D_CPU1_SA_CB<0>
  VSS21  = GND
  CB1_A  = M_D_CPU1_SA_CB<1>
  VSS22  = GND
  DQS4_A_T  = M_D_CPU1_SA_DQS_DP<4>
  DQS4_A_C  = M_D_CPU1_SA_DQS_DN<4>
  VSS23  = GND
  CB4_A  = M_D_CPU1_SA_CB<4>
  VSS24  = GND
  CB5_A  = M_D_CPU1_SA_CB<5>
  VSS25  = GND
  ALERT_N  = M_D_CPU1_ALERT_N
  VSS26  = GND
  CS0_A_N  = M_D_CPU1_SA_CS_N<0>
  VSS27  = GND
  CA0_A  = M_D_CPU1_SA_CA<0>
  VSS28  = GND
  CA2_A  = M_D_CPU1_SA_CA<2>
  VSS29  = GND
  CA4_A  = M_D_CPU1_SA_CA<4>
  VSS30  = GND
  CA6_A  = M_D_CPU1_SA_CA<6>
  VSS31  = GND
  PAR_A  = M_D_CPU1_SA_PAR
  VSS32  = GND
  CA0_B  = M_D_CPU1_SB_CA<0>
  VSS33  = GND
  CA2_B  = M_D_CPU1_SB_CA<2>
  VSS34  = GND
  CA4_B  = M_D_CPU1_SB_CA<4>
  VSS35  = GND
  CA6_B  = M_D_CPU1_SB_CA<6>
  VSS36  = GND
  CS0_B_N  = M_D_CPU1_SB_CS_N<0>
  VSS37  = GND
  \lbd||rsp_a_n\  = M_D_CPU1_SA_RSP<0>
  \lbs||rsp_b_n\  = M_D_CPU1_SB_RSP<0>
  VSS38  = GND
  CB4_B  = M_D_CPU1_SB_CB<4>
  VSS39  = GND
  CB5_B  = M_D_CPU1_SB_CB<5>
  VSS40  = GND
  \dqs9_b_t||tdqs9_b_t||dbi4_b_n\  = M_D_CPU1_SB_DQS_DP<9>
  \dqs9_b_c||tdqs9_b_c\  = M_D_CPU1_SB_DQS_DN<9>
  VSS41  = GND
  CB0_B  = M_D_CPU1_SB_CB<0>
  VSS42  = GND
  CB1_B  = M_D_CPU1_SB_CB<1>
  VSS43  = GND
  DQ0_B  = M_D_CPU1_SB_DQ<0>
  VSS44  = GND
  DQ1_B  = M_D_CPU1_SB_DQ<1>
  VSS45  = GND
  DQS0_B_T  = M_D_CPU1_SB_DQS_DP<0>
  DQS0_B_C  = M_D_CPU1_SB_DQS_DN<0>
  VSS46  = GND
  DQ4_B  = M_D_CPU1_SB_DQ<4>
  VSS47  = GND
  DQ5_B  = M_D_CPU1_SB_DQ<5>
  VSS48  = GND
  DQ8_B  = M_D_CPU1_SB_DQ<8>
  VSS49  = GND
  DQ9_B  = M_D_CPU1_SB_DQ<9>
  VSS50  = GND
  DQS1_B_T  = M_D_CPU1_SB_DQS_DP<1>
  DQS1_B_C  = M_D_CPU1_SB_DQS_DN<1>
  VSS51  = GND
  DQ12_B  = M_D_CPU1_SB_DQ<12>
  VSS52  = GND
  DQ13_B  = M_D_CPU1_SB_DQ<13>
  VSS53  = GND
  DQ16_B  = M_D_CPU1_SB_DQ<16>
  VSS54  = GND
  DQ17_B  = M_D_CPU1_SB_DQ<17>
  VSS55  = GND
  DQS2_B_T  = M_D_CPU1_SB_DQS_DP<2>
  DQS2_B_C  = M_D_CPU1_SB_DQS_DN<2>
  VSS56  = GND
  DQ20_B  = M_D_CPU1_SB_DQ<20>
  VSS57  = GND
  DQ21_B  = M_D_CPU1_SB_DQ<21>
  VSS58  = GND
  DQ24_B  = M_D_CPU1_SB_DQ<24>
  VSS59  = GND
  DQ25_B  = M_D_CPU1_SB_DQ<25>
  VSS60  = GND
  DQS3_B_T  = M_D_CPU1_SB_DQS_DP<3>
  DQS3_B_C  = M_D_CPU1_SB_DQS_DN<3>
  VSS61  = GND
  DQ28_B  = M_D_CPU1_SB_DQ<28>
  VSS62  = GND
  DQ29_B  = M_D_CPU1_SB_DQ<29>
  VSS63  = GND
  RFU1  = NC
  VIN_BULK1  = P12V_MEM_CPU1
  VIN_BULK2  = P12V_MEM_CPU1
  \pwr_good||fail_n\  = PWRGD_CHD_CPU1_DIMM
  HAS  = PD_CHD_CPU1_DIMM_SAA
  RFU2  = NC
  RFU3  = NC
  VSS64  = GND
  DQ2_A  = M_D_CPU1_SA_DQ<2>
  VSS65  = GND
  DQ3_A  = M_D_CPU1_SA_DQ<3>
  VSS66  = GND
  \dqs5_a_c||tdqs5_a_c||dqs5_a_t||tdqs5_a_t\  = M_D_CPU1_SA_DQS_DN<5>
  \dqs5_a_t||tdqs5_a_t\  = M_D_CPU1_SA_DQS_DP<5>
  VSS67  = GND
  DQ6_A  = M_D_CPU1_SA_DQ<6>
  VSS68  = GND
  DQ7_A  = M_D_CPU1_SA_DQ<7>
  VSS69  = GND
  DQ10_A  = M_D_CPU1_SA_DQ<10>
  VSS70  = GND
  DQ11_A  = M_D_CPU1_SA_DQ<11>
  VSS71  = GND
  \dqs6_a_c||tdqs6_a_c||dqs6_a_t||tdqs6_a_t\  = M_D_CPU1_SA_DQS_DN<6>
  \dqs6_a_t||tdqs6_a_t\  = M_D_CPU1_SA_DQS_DP<6>
  VSS72  = GND
  DQ14_A  = M_D_CPU1_SA_DQ<14>
  VSS73  = GND
  DQ15_A  = M_D_CPU1_SA_DQ<15>
  VSS74  = GND
  DQ18_A  = M_D_CPU1_SA_DQ<18>
  VSS75  = GND
  DQ19_A  = M_D_CPU1_SA_DQ<19>
  VSS76  = GND
  \dqs7_a_c||tdqs7_a_c\  = M_D_CPU1_SA_DQS_DN<7>
  \dqs7_a_t||tdqs7_a_t\  = M_D_CPU1_SA_DQS_DP<7>
  VSS77  = GND
  DQ22_A  = M_D_CPU1_SA_DQ<22>
  VSS78  = GND
  DQ23_A  = M_D_CPU1_SA_DQ<23>
  VSS79  = GND
  DQ26_A  = M_D_CPU1_SA_DQ<26>
  VSS80  = GND
  DQ27_A  = M_D_CPU1_SA_DQ<27>
  VSS81  = GND
  \dqs8_a_c||tdqs8_a_c\  = M_D_CPU1_SA_DQS_DN<8>
  \dqs8_a_t||tdqs8_a_t\  = M_D_CPU1_SA_DQS_DP<8>
  VSS82  = GND
  DQ30_A  = M_D_CPU1_SA_DQ<30>
  VSS83  = GND
  DQ31_A  = M_D_CPU1_SA_DQ<31>
  VSS84  = GND
  CB2_A  = M_D_CPU1_SA_CB<2>
  VSS85  = GND
  CB3_A  = M_D_CPU1_SA_CB<3>
  VSS86  = GND
  \dqs9_a_c||tdqs9_a_c\  = M_D_CPU1_SA_DQS_DN<9>
  \dqs9_a_t||tdqs9_a_t\  = M_D_CPU1_SA_DQS_DP<9>
  VSS87  = GND
  CB6_A  = M_D_CPU1_SA_CB<6>
  VSS88  = GND
  CB7_A  = M_D_CPU1_SA_CB<7>
  VSS89  = GND
  RESET_N  = M_D_CPU1_RESET_N
  VSS90  = GND
  CS1_A_N  = M_D_CPU1_SA_CS_N<1>
  VSS91  = GND
  CA1_A  = M_D_CPU1_SA_CA<1>
  VSS92  = GND
  CA3_A  = M_D_CPU1_SA_CA<3>
  VSS93  = GND
  CA5_A  = M_D_CPU1_SA_CA<5>
  VSS94  = GND
  CK_T  = M_D_CPU1_CLK_DP<0>
  CK_C  = M_D_CPU1_CLK_DN<0>
  VSS95  = GND
  RFU4  = NC
  CA1_B  = M_D_CPU1_SB_CA<1>
  VSS96  = GND
  CA3_B  = M_D_CPU1_SB_CA<3>
  VSS97  = GND
  CA5_B  = M_D_CPU1_SB_CA<5>
  VSS98  = GND
  PAR_B  = M_D_CPU1_SB_PAR
  VSS99  = GND
  CS1_B_N  = M_D_CPU1_SB_CS_N<1>
  VSS100  = GND
  RFU5  = NC
  RFU6  = NC
  VSS101  = GND
  CB6_B  = M_D_CPU1_SB_CB<6>
  VSS102  = GND
  CB7_B  = M_D_CPU1_SB_CB<7>
  VSS103  = GND
  DQS4_B_C  = M_D_CPU1_SB_DQS_DN<4>
  DQS4_B_T  = M_D_CPU1_SB_DQS_DP<4>
  VSS104  = GND
  CB2_B  = M_D_CPU1_SB_CB<2>
  VSS105  = GND
  CB3_B  = M_D_CPU1_SB_CB<3>
  VSS106  = GND
  DQ2_B  = M_D_CPU1_SB_DQ<2>
  VSS107  = GND
  DQ3_B  = M_D_CPU1_SB_DQ<3>
  VSS108  = GND
  \dqs5_b_c||tdqs5_b_c\  = M_D_CPU1_SB_DQS_DN<5>
  \dqs5_b_t||tdqs5_b_t\  = M_D_CPU1_SB_DQS_DP<5>
  VSS109  = GND
  DQ6_B  = M_D_CPU1_SB_DQ<6>
  VSS110  = GND
  DQ7_B  = M_D_CPU1_SB_DQ<7>
  VSS111  = GND
  DQ10_B  = M_D_CPU1_SB_DQ<10>
  VSS112  = GND
  DQ11_B  = M_D_CPU1_SB_DQ<11>
  VSS113  = GND
  \dqs6_b_c||tdqs6_b_c\  = M_D_CPU1_SB_DQS_DN<6>
  \dqs6_b_t||tdqs6_b_t\  = M_D_CPU1_SB_DQS_DP<6>
  VSS114  = GND
  DQ14_B  = M_D_CPU1_SB_DQ<14>
  VSS115  = GND
  DQ15_B  = M_D_CPU1_SB_DQ<15>
  VSS116  = GND
  DQ18_B  = M_D_CPU1_SB_DQ<18>
  VSS117  = GND
  DQ19_B  = M_D_CPU1_SB_DQ<19>
  VSS118  = GND
  \dqs7_b_c||tdqs7_b_c\  = M_D_CPU1_SB_DQS_DN<7>
  \dqs7_b_t||tdqs7_b_t\  = M_D_CPU1_SB_DQS_DP<7>
  VSS119  = GND
  DQ22_B  = M_D_CPU1_SB_DQ<22>
  VSS120  = GND
  DQ23_B  = M_D_CPU1_SB_DQ<23>
  VSS121  = GND
  DQ26_B  = M_D_CPU1_SB_DQ<26>
  VSS122  = GND
  DQ27_B  = M_D_CPU1_SB_DQ<27>
  VSS123  = GND
  \dqs8_b_c||tdqs8_b_c\  = M_D_CPU1_SB_DQS_DN<8>
  \dqs8_b_t||tdqs8_b_t\  = M_D_CPU1_SB_DQS_DP<8>
  VSS124  = GND
  DQ30_B  = M_D_CPU1_SB_DQ<30>
  VSS125  = GND
  DQ31_B  = M_D_CPU1_SB_DQ<31>
  VSS126  = GND
  G1  = GND
  G2  = GND
  G3  = GND

(kicad_pcb
	(version 20260206)
	(generator "pcbnew")
	(generator_version "10.0")
	(general
		(thickness 1.6)
		(legacy_teardrops no)
	)
	(paper "A4")
	(title_block
		(title "04192023_DAF0TMB3IC0_F0TG_MB_C_brd_V02_OCP.brd")
		(comment 1 "Grand Teton / footprint 3579 of 8354 (J30), pads 1-46 of 291")
	)
	(layers
		(0 "F.Cu" signal "TOP")
		(4 "In1.Cu" signal "GND")
		(6 "In2.Cu" signal "IN1")
		(8 "In3.Cu" signal "GND1")
		(10 "In4.Cu" signal "IN2")
		(12 "In5.Cu" signal "GND2")
		(14 "In6.Cu" signal "IN3")
		(16 "In7.Cu" signal "GND3")
		(18 "In8.Cu" signal "VCC")
		(20 "In9.Cu" signal "VCC1")
		(22 "In10.Cu" signal "GND4")
		(24 "In11.Cu" signal "IN4")
		(26 "In12.Cu" signal "GND5")
		(28 "In13.Cu" signal "IN5")
		(30 "In14.Cu" signal "GND6")
		(32 "In15.Cu" signal "IN6")
		(34 "In16.Cu" signal "GND7")
		(2 "B.Cu" signal "BOTTOM")
		(9 "F.Adhes" user "F.Adhesive")
		(11 "B.Adhes" user "B.Adhesive")
		(13 "F.Paste" user "Package Geometry/Pastemask Top")
		(15 "B.Paste" user "Package Geometry/Pastemask Bottom")
		(5 "F.SilkS" user "Ref Des/Silkscreen Top")
		(7 "B.SilkS" user "Ref Des/Silkscreen Bottom")
		(1 "F.Mask" user "Board Geometry/Soldermask Top")
		(3 "B.Mask" user "Board Geometry/Soldermask Bottom")
		(17 "Dwgs.User" user "User.Drawings")
		(19 "Cmts.User" user "User.Comments")
		(21 "Eco1.User" user "User.Eco1")
		(23 "Eco2.User" user "User.Eco2")
		(25 "Edge.Cuts" user "Board Geometry/Outline")
		(27 "Margin" user)
		(31 "F.CrtYd" user "Package Geometry/Place Bound Top")
		(29 "B.CrtYd" user "Package Geometry/Place Bound Bottom")
		(35 "F.Fab" user "Ref Des/Assembly Top")
		(33 "B.Fab" user "Ref Des/Assembly Bottom")
	)
	(footprint ""
		(layer "F.Cu")
		(at 34.74593 -255.560322 180)
		(property "Reference" "J30"
			(at 3.12293 -81.850992 0)
			(unlocked yes)
			(layer "F.SilkS")
			(effects
				(font
					(size 0.7874 0.5842)
					(thickness 0.1524)
				)
			)
		)
		(property "Value" ""
			(at 0 0 180)
			(layer "F.Fab")
			(effects
				(font
					(size 1.27 1.27)
				)
			)
		)
		(duplicate_pad_numbers_are_jumpers no)
		(pad "1" smd rect
			(at -2.050034 -63.324994 90)
			(size 0.519938 1.4986)
			(layers "F.Cu" "F.Mask" "F.Paste")
			(net "P12V_MEM_CPU1")
		)
		(pad "2" smd rect
			(at -2.050034 -62.47511 90)
			(size 0.519938 1.4986)
			(layers "F.Cu" "F.Mask" "F.Paste")
			(net "Net_2298")
		)
		(pad "3" smd rect
			(at -2.050034 -61.624972 90)
			(size 0.519938 1.4986)
			(layers "F.Cu" "F.Mask" "F.Paste")
			(net "P3V3_AUX")
		)
		(pad "4" smd rect
			(at -2.050034 -60.775088 90)
			(size 0.519938 1.4986)
			(layers "F.Cu" "F.Mask" "F.Paste")
			(net "I3C_SPD_DDRD_CPU1_SCL")
		)
		(pad "5" smd rect
			(at -2.050034 -59.92495 90)
			(size 0.519938 1.4986)
			(layers "F.Cu" "F.Mask" "F.Paste")
			(net "I3C_SPD_DDRD_CPU1_SDA")
		)
		(pad "6" smd rect
			(at -2.050034 -59.075066 90)
			(size 0.519938 1.4986)
			(layers "F.Cu" "F.Mask" "F.Paste")
			(net "GND")
		)
		(pad "7" smd rect
			(at -2.050034 -58.224928 90)
			(size 0.519938 1.4986)
			(layers "F.Cu" "F.Mask" "F.Paste")
			(net "M_D_CPU1_SA_DQ<0>")
		)
		(pad "8" smd rect
			(at -2.050034 -57.375044 90)
			(size 0.519938 1.4986)
			(layers "F.Cu" "F.Mask" "F.Paste")
			(net "GND")
		)
		(pad "9" smd rect
			(at -2.050034 -56.524906 90)
			(size 0.519938 1.4986)
			(layers "F.Cu" "F.Mask" "F.Paste")
			(net "M_D_CPU1_SA_DQ<1>")
		)
		(pad "10" smd rect
			(at -2.050034 -55.675022 90)
			(size 0.519938 1.4986)
			(layers "F.Cu" "F.Mask" "F.Paste")
			(net "GND")
		)
		(pad "11" smd rect
			(at -2.050034 -54.824884 90)
			(size 0.519938 1.4986)
			(layers "F.Cu" "F.Mask" "F.Paste")
			(net "M_D_CPU1_SA_DQS_DP<0>")
		)
		(pad "12" smd rect
			(at -2.050034 -53.975 90)
			(size 0.519938 1.4986)
			(layers "F.Cu" "F.Mask" "F.Paste")
			(net "M_D_CPU1_SA_DQS_DN<0>")
		)
		(pad "13" smd rect
			(at -2.050034 -53.125116 90)
			(size 0.519938 1.4986)
			(layers "F.Cu" "F.Mask" "F.Paste")
			(net "GND")
		)
		(pad "14" smd rect
			(at -2.050034 -52.274978 90)
			(size 0.519938 1.4986)
			(layers "F.Cu" "F.Mask" "F.Paste")
			(net "M_D_CPU1_SA_DQ<4>")
		)
		(pad "15" smd rect
			(at -2.050034 -51.425094 90)
			(size 0.519938 1.4986)
			(layers "F.Cu" "F.Mask" "F.Paste")
			(net "GND")
		)
		(pad "16" smd rect
			(at -2.050034 -50.574956 90)
			(size 0.519938 1.4986)
			(layers "F.Cu" "F.Mask" "F.Paste")
			(net "M_D_CPU1_SA_DQ<5>")
		)
		(pad "17" smd rect
			(at -2.050034 -49.725072 90)
			(size 0.519938 1.4986)
			(layers "F.Cu" "F.Mask" "F.Paste")
			(net "GND")
		)
		(pad "18" smd rect
			(at -2.050034 -48.874934 90)
			(size 0.519938 1.4986)
			(layers "F.Cu" "F.Mask" "F.Paste")
			(net "M_D_CPU1_SA_DQ<8>")
		)
		(pad "19" smd rect
			(at -2.050034 -48.02505 90)
			(size 0.519938 1.4986)
			(layers "F.Cu" "F.Mask" "F.Paste")
			(net "GND")
		)
		(pad "20" smd rect
			(at -2.050034 -47.174912 90)
			(size 0.519938 1.4986)
			(layers "F.Cu" "F.Mask" "F.Paste")
			(net "M_D_CPU1_SA_DQ<9>")
		)
		(pad "21" smd rect
			(at -2.050034 -46.325028 90)
			(size 0.519938 1.4986)
			(layers "F.Cu" "F.Mask" "F.Paste")
			(net "GND")
		)
		(pad "22" smd rect
			(at -2.050034 -45.47489 90)
			(size 0.519938 1.4986)
			(layers "F.Cu" "F.Mask" "F.Paste")
			(net "M_D_CPU1_SA_DQS_DP<1>")
		)
		(pad "23" smd rect
			(at -2.050034 -44.625006 90)
			(size 0.519938 1.4986)
			(layers "F.Cu" "F.Mask" "F.Paste")
			(net "M_D_CPU1_SA_DQS_DN<1>")
		)
		(pad "24" smd rect
			(at -2.050034 -43.775122 90)
			(size 0.519938 1.4986)
			(layers "F.Cu" "F.Mask" "F.Paste")
			(net "GND")
		)
		(pad "25" smd rect
			(at -2.050034 -42.924984 90)
			(size 0.519938 1.4986)
			(layers "F.Cu" "F.Mask" "F.Paste")
			(net "M_D_CPU1_SA_DQ<12>")
		)
		(pad "26" smd rect
			(at -2.050034 -42.0751 90)
			(size 0.519938 1.4986)
			(layers "F.Cu" "F.Mask" "F.Paste")
			(net "GND")
		)
		(pad "27" smd rect
			(at -2.050034 -41.224962 90)
			(size 0.519938 1.4986)
			(layers "F.Cu" "F.Mask" "F.Paste")
			(net "M_D_CPU1_SA_DQ<13>")
		)
		(pad "28" smd rect
			(at -2.050034 -40.375078 90)
			(size 0.519938 1.4986)
			(layers "F.Cu" "F.Mask" "F.Paste")
			(net "GND")
		)
		(pad "29" smd rect
			(at -2.050034 -39.52494 90)
			(size 0.519938 1.4986)
			(layers "F.Cu" "F.Mask" "F.Paste")
			(net "M_D_CPU1_SA_DQ<16>")
		)
		(pad "30" smd rect
			(at -2.050034 -38.675056 90)
			(size 0.519938 1.4986)
			(layers "F.Cu" "F.Mask" "F.Paste")
			(net "GND")
		)
		(pad "31" smd rect
			(at -2.050034 -37.824918 90)
			(size 0.519938 1.4986)
			(layers "F.Cu" "F.Mask" "F.Paste")
			(net "M_D_CPU1_SA_DQ<17>")
		)
		(pad "32" smd rect
			(at -2.050034 -36.975034 90)
			(size 0.519938 1.4986)
			(layers "F.Cu" "F.Mask" "F.Paste")
			(net "GND")
		)
		(pad "33" smd rect
			(at -2.050034 -36.124896 90)
			(size 0.519938 1.4986)
			(layers "F.Cu" "F.Mask" "F.Paste")
			(net "M_D_CPU1_SA_DQS_DP<2>")
		)
		(pad "34" smd rect
			(at -2.050034 -35.275012 90)
			(size 0.519938 1.4986)
			(layers "F.Cu" "F.Mask" "F.Paste")
			(net "M_D_CPU1_SA_DQS_DN<2>")
		)
		(pad "35" smd rect
			(at -2.050034 -34.425128 90)
			(size 0.519938 1.4986)
			(layers "F.Cu" "F.Mask" "F.Paste")
			(net "GND")
		)
		(pad "36" smd rect
			(at -2.050034 -33.57499 90)
			(size 0.519938 1.4986)
			(layers "F.Cu" "F.Mask" "F.Paste")
			(net "M_D_CPU1_SA_DQ<20>")
		)
		(pad "37" smd rect
			(at -2.050034 -32.725106 90)
			(size 0.519938 1.4986)
			(layers "F.Cu" "F.Mask" "F.Paste")
			(net "GND")
		)
		(pad "38" smd rect
			(at -2.050034 -31.874968 90)
			(size 0.519938 1.4986)
			(layers "F.Cu" "F.Mask" "F.Paste")
			(net "M_D_CPU1_SA_DQ<21>")
		)
		(pad "39" smd rect
			(at -2.050034 -31.025084 90)
			(size 0.519938 1.4986)
			(layers "F.Cu" "F.Mask" "F.Paste")
			(net "GND")
		)
		(pad "40" smd rect
			(at -2.050034 -30.174946 90)
			(size 0.519938 1.4986)
			(layers "F.Cu" "F.Mask" "F.Paste")
			(net "M_D_CPU1_SA_DQ<24>")
		)
		(pad "41" smd rect
			(at -2.050034 -29.325062 90)
			(size 0.519938 1.4986)
			(layers "F.Cu" "F.Mask" "F.Paste")
			(net "GND")
		)
		(pad "42" smd rect
			(at -2.050034 -28.474924 90)
			(size 0.519938 1.4986)
			(layers "F.Cu" "F.Mask" "F.Paste")
			(net "M_D_CPU1_SA_DQ<25>")
		)
		(pad "43" smd rect
			(at -2.050034 -27.62504 90)
			(size 0.519938 1.4986)
			(layers "F.Cu" "F.Mask" "F.Paste")
			(net "GND")
		)
		(pad "44" smd rect
			(at -2.050034 -26.774902 90)
			(size 0.519938 1.4986)
			(layers "F.Cu" "F.Mask" "F.Paste")
			(net "M_D_CPU1_SA_DQS_DP<3>")
		)
		(pad "45" smd rect
			(at -2.050034 -25.925018 90)
			(size 0.519938 1.4986)
			(layers "F.Cu" "F.Mask" "F.Paste")
			(net "M_D_CPU1_SA_DQS_DN<3>")
		)
		(pad "46" smd rect
			(at -2.050034 -25.07488 90)
			(size 0.519938 1.4986)
			(layers "F.Cu" "F.Mask" "F.Paste")
			(net "GND")
		)
	)
)
